(kicad_pcb
	(version 20260206)
	(generator "pcbnew")
	(generator_version "10.0")
	(general
		(thickness 1.6)
		(legacy_teardrops no)
	)
	(paper "A4")
	(title_block
		(title "03242023_DA0F0TMBIJ0_F0T_Motherboard_J_brd_V01_OCP.brd")
		(comment 1 "Grand Teton / footprints 2465-2465 of 6105")
	)
	(layers
		(0 "F.Cu" signal "TOP")
		(4 "In1.Cu" signal "GND")
		(6 "In2.Cu" signal "IN1")
		(8 "In3.Cu" signal "GND1")
		(10 "In4.Cu" signal "IN2")
		(12 "In5.Cu" signal "GND2")
		(14 "In6.Cu" signal "IN3")
		(16 "In7.Cu" signal "GND3")
		(18 "In8.Cu" signal "VCC")
		(20 "In9.Cu" signal "VCC1")
		(22 "In10.Cu" signal "GND4")
		(24 "In11.Cu" signal "IN4")
		(26 "In12.Cu" signal "GND5")
		(28 "In13.Cu" signal "IN5")
		(30 "In14.Cu" signal "GND6")
		(32 "In15.Cu" signal "IN6")
		(34 "In16.Cu" signal "GND7")
		(2 "B.Cu" signal "BOTTOM")
		(9 "F.Adhes" user "F.Adhesive")
		(11 "B.Adhes" user "B.Adhesive")
		(13 "F.Paste" user "Package Geometry/Pastemask Top")
		(15 "B.Paste" user "Package Geometry/Pastemask Bottom")
		(5 "F.SilkS" user "Ref Des/Silkscreen Top")
		(7 "B.SilkS" user "Ref Des/Silkscreen Bottom")
		(1 "F.Mask" user "Board Geometry/Soldermask Top")
		(3 "B.Mask" user "Board Geometry/Soldermask Bottom")
		(17 "Dwgs.User" user "User.Drawings")
		(19 "Cmts.User" user "User.Comments")
		(21 "Eco1.User" user "User.Eco1")
		(23 "Eco2.User" user "User.Eco2")
		(25 "Edge.Cuts" user "Board Geometry/Outline")
		(27 "Margin" user)
		(31 "F.CrtYd" user "Package Geometry/Place Bound Top")
		(29 "B.CrtYd" user "Package Geometry/Place Bound Bottom")
		(35 "F.Fab" user "Ref Des/Assembly Top")
		(33 "B.Fab" user "Ref Des/Assembly Bottom")
	)
	(footprint ""
		(layer "F.Cu")
		(at 108.578396 -358.848406 -90)
		(property "Reference" "PU29"
			(at 8.473948 -1.629664 0)
			(unlocked yes)
			(layer "F.SilkS")
			(effects
				(font
					(size 0.7874 0.5842)
					(thickness 0.1524)
				)
				(justify left)
			)
		)
		(property "Value" ""
			(at 0 0 270)
			(layer "F.Fab")
			(effects
				(font
					(size 1.27 1.27)
				)
			)
		)
		(duplicate_pad_numbers_are_jumpers no)
		(fp_line
			(start -1.400048 3.86969)
			(end -1.400048 3.36169)
			(stroke
				(width 0.1524)
				(type default)
			)
			(layer "F.SilkS")
		)
		(fp_line
			(start 0.599948 3.366008)
			(end 0.599948 4.255008)
			(stroke
				(width 0.1524)
				(type default)
			)
			(layer "F.SilkS")
		)
		(fp_line
			(start -2.999994 2.999994)
			(end -2.999994 2.490978)
			(stroke
				(width 0.1524)
				(type default)
			)
			(layer "F.SilkS")
		)
		(fp_line
			(start -2.518156 2.999994)
			(end -2.999994 2.999994)
			(stroke
				(width 0.1524)
				(type default)
			)
			(layer "F.SilkS")
		)
		(fp_line
			(start 2.999994 2.999994)
			(end 2.47015 2.999994)
			(stroke
				(width 0.1524)
				(type default)
			)
			(layer "F.SilkS")
		)
		(fp_line
			(start 2.999994 2.490978)
			(end 2.999994 2.999994)
			(stroke
				(width 0.1524)
				(type default)
			)
			(layer "F.SilkS")
		)
		(fp_line
			(start 3.3782 2.199894)
			(end 3.8862 2.199894)
			(stroke
				(width 0.1524)
				(type default)
			)
			(layer "F.SilkS")
		)
		(fp_line
			(start -3.3782 1.400048)
			(end -4.2672 1.400048)
			(stroke
				(width 0.1524)
				(type default)
			)
			(layer "F.SilkS")
		)
		(fp_line
			(start 3.3528 0.199898)
			(end 4.2418 0.199898)
			(stroke
				(width 0.1524)
				(type default)
			)
			(layer "F.SilkS")
		)
		(fp_line
			(start -3.3782 -0.599948)
			(end -3.7592 -0.599948)
			(stroke
				(width 0.1524)
				(type default)
			)
			(layer "F.SilkS")
		)
		(fp_line
			(start 3.3528 -1.800098)
			(end 3.8608 -1.800098)
			(stroke
				(width 0.1524)
				(type default)
			)
			(layer "F.SilkS")
		)
		(fp_line
			(start -2.999994 -2.438654)
			(end -2.999994 -2.999994)
			(stroke
				(width 0.1524)
				(type default)
			)
			(layer "F.SilkS")
		)
		(fp_line
			(start -2.999994 -2.999994)
			(end -2.489962 -2.999994)
			(stroke
				(width 0.1524)
				(type default)
			)
			(layer "F.SilkS")
		)
		(fp_line
			(start 2.437384 -2.999994)
			(end 2.999994 -2.999994)
			(stroke
				(width 0.1524)
				(type default)
			)
			(layer "F.SilkS")
		)
		(fp_line
			(start 2.999994 -2.999994)
			(end 2.999994 -2.471166)
			(stroke
				(width 0.1524)
				(type default)
			)
			(layer "F.SilkS")
		)
		(fp_line
			(start -0.999998 -3.3782)
			(end -0.999998 -3.8862)
			(stroke
				(width 0.1524)
				(type default)
			)
			(layer "F.SilkS")
		)
		(fp_line
			(start 0.999998 -4.2545)
			(end 0.999998 -3.3655)
			(stroke
				(width 0.1524)
				(type default)
			)
			(layer "F.SilkS")
		)
		(fp_poly
			(pts
				(xy -3.299206 -2.199894) (xy -3.6449 -2.050034) (xy -3.6449 -2.352294)
			)
			(stroke
				(width 0)
				(type default)
			)
			(fill yes)
			(layer "F.SilkS")
		)
		(fp_line
			(start -1.400048 3.86969)
			(end -1.400048 3.36169)
			(stroke
				(width 0.1)
				(type default)
			)
			(layer "F.Fab")
		)
		(fp_line
			(start 0.599948 3.366008)
			(end 0.599948 4.255008)
			(stroke
				(width 0.1)
				(type default)
			)
			(layer "F.Fab")
		)
		(fp_line
			(start -2.999994 2.999994)
			(end -2.999994 -2.999994)
			(stroke
				(width 0.1)
				(type default)
			)
			(layer "F.Fab")
		)
		(fp_line
			(start 2.999994 2.999994)
			(end -2.999994 2.999994)
			(stroke
				(width 0.1)
				(type default)
			)
			(layer "F.Fab")
		)
		(fp_line
			(start 3.3782 2.199894)
			(end 3.8862 2.199894)
			(stroke
				(width 0.1)
				(type default)
			)
			(layer "F.Fab")
		)
		(fp_line
			(start -3.3782 1.400048)
			(end -4.2672 1.400048)
			(stroke
				(width 0.1)
				(type default)
			)
			(layer "F.Fab")
		)
		(fp_line
			(start 3.3528 0.199898)
			(end 4.2418 0.199898)
			(stroke
				(width 0.1)
				(type default)
			)
			(layer "F.Fab")
		)
		(fp_line
			(start -3.3782 -0.599948)
			(end -3.7592 -0.599948)
			(stroke
				(width 0.1)
				(type default)
			)
			(layer "F.Fab")
		)
		(fp_line
			(start 3.3528 -1.800098)
			(end 3.8608 -1.800098)
			(stroke
				(width 0.1)
				(type default)
			)
			(layer "F.Fab")
		)
		(fp_line
			(start -2.999994 -2.999994)
			(end 2.999994 -2.999994)
			(stroke
				(width 0.1)
				(type default)
			)
			(layer "F.Fab")
		)
		(fp_line
			(start 2.999994 -2.999994)
			(end 2.999994 2.999994)
			(stroke
				(width 0.1)
				(type default)
			)
			(layer "F.Fab")
		)
		(fp_line
			(start -0.999998 -3.3782)
			(end -0.999998 -3.8862)
			(stroke
				(width 0.1)
				(type default)
			)
			(layer "F.Fab")
		)
		(fp_line
			(start 0.999998 -4.2545)
			(end 0.999998 -3.3655)
			(stroke
				(width 0.1)
				(type default)
			)
			(layer "F.Fab")
		)
		(fp_poly
			(pts
				(xy -3.6449 -2.352294) (xy -3.6449 -2.050034) (xy -3.299206 -2.199894)
			)
			(stroke
				(width 0)
				(type default)
			)
			(fill yes)
			(layer "F.Fab")
		)
		(fp_text user "24"
			(at 2.807716 4.885436 0)
			(unlocked yes)
			(layer "F.SilkS")
			(effects
				(font
					(size 0.7874 0.5842)
					(thickness 0.1524)
				)
				(justify left)
			)
		)
		(fp_text user "13"
			(at -2.514092 4.717796 0)
			(unlocked yes)
			(layer "F.SilkS")
			(effects
				(font
					(size 0.7874 0.5842)
					(thickness 0.1524)
				)
				(justify left)
			)
		)
		(fp_text user "25"
			(at 3.765296 3.948176 0)
			(unlocked yes)
			(layer "F.SilkS")
			(effects
				(font
					(size 0.7874 0.5842)
					(thickness 0.1524)
				)
				(justify left)
			)
		)
		(fp_text user "12"
			(at -3.999992 2.645156 0)
			(unlocked yes)
			(layer "F.SilkS")
			(effects
				(font
					(size 0.7874 0.5842)
					(thickness 0.1524)
				)
				(justify left)
			)
		)
		(fp_text user "36"
			(at 4.059428 -2.137664 0)
			(unlocked yes)
			(layer "F.SilkS")
			(effects
				(font
					(size 0.7874 0.5842)
					(thickness 0.1524)
				)
				(justify left)
			)
		)
		(fp_text user "48"
			(at -4.530852 -2.157984 0)
			(unlocked yes)
			(layer "F.SilkS")
			(effects
				(font
					(size 0.7874 0.5842)
					(thickness 0.1524)
				)
				(justify left)
			)
		)
		(fp_text user "48"
			(at -1.754632 -3.547364 0)
			(unlocked yes)
			(layer "F.SilkS")
			(effects
				(font
					(size 0.7874 0.5842)
					(thickness 0.1524)
				)
				(justify left)
			)
		)
		(fp_text user "37"
			(at 2.908808 -3.547364 0)
			(unlocked yes)
			(layer "F.SilkS")
			(effects
				(font
					(size 0.7874 0.5842)
					(thickness 0.1524)
				)
				(justify left)
			)
		)
		(fp_text user "13"
			(at -3.5814 3.794252 270)
			(unlocked yes)
			(layer "F.Fab")
			(effects
				(font
					(size 0.7874 0.5842)
					(thickness 0.1524)
				)
				(justify left)
			)
		)
		(fp_text user "24"
			(at 2.1844 3.768852 270)
			(unlocked yes)
			(layer "F.Fab")
			(effects
				(font
					(size 0.7874 0.5842)
					(thickness 0.1524)
				)
				(justify left)
			)
		)
		(fp_text user "25"
			(at 3.2004 2.829052 270)
			(unlocked yes)
			(layer "F.Fab")
			(effects
				(font
					(size 0.7874 0.5842)
					(thickness 0.1524)
				)
				(justify left)
			)
		)
		(fp_text user "12"
			(at -4.6228 2.752852 270)
			(unlocked yes)
			(layer "F.Fab")
			(effects
				(font
					(size 0.7874 0.5842)
					(thickness 0.1524)
				)
				(justify left)
			)
		)
		(fp_text user "36"
			(at 3.2258 -2.733548 270)
			(unlocked yes)
			(layer "F.Fab")
			(effects
				(font
					(size 0.7874 0.5842)
					(thickness 0.1524)
				)
				(justify left)
			)
		)
		(fp_text user "37"
			(at 2.2352 -3.724148 270)
			(unlocked yes)
			(layer "F.Fab")
			(effects
				(font
					(size 0.7874 0.5842)
					(thickness 0.1524)
				)
				(justify left)
			)
		)
		(fp_text user "48"
			(at -3.509264 -3.740658 270)
			(unlocked yes)
			(layer "F.Fab")
			(effects
				(font
					(size 0.7874 0.5842)
					(thickness 0.1524)
				)
				(justify left)
			)
		)
		(pad "1" smd rect
			(at -2.875026 -2.199894)
			(size 0.1778 0.6604)
			(layers "F.Cu" "F.Mask" "F.Paste")
			(net "PVCCFA_EHV_FIVRA_CPU1_PWM1")
		)
		(pad "2" smd rect
			(at -2.875026 -1.800098)
			(size 0.1778 0.6604)
			(layers "F.Cu" "F.Mask" "F.Paste")
			(net "PVCCFA_EHV_FIVRA_CPU1_PWM2")
		)
		(pad "3" smd rect
			(at -2.875026 -1.400048)
			(size 0.1778 0.6604)
			(layers "F.Cu" "F.Mask" "F.Paste")
			(net "PVCCFA_EHV_FIVRA_CPU1_PWM3")
		)
		(pad "4" smd rect
			(at -2.875026 -0.999998)
			(size 0.1778 0.6604)
			(layers "F.Cu" "F.Mask" "F.Paste")
			(net "PVCCFA_EHV_FIVRA_CPU1_PWM4")
		)
		(pad "5" smd rect
			(at -2.875026 -0.599948)
			(size 0.1778 0.6604)
			(layers "F.Cu" "F.Mask" "F.Paste")
			(net "PVCCIN_CPU1_PWM8")
		)
		(pad "6" smd rect
			(at -2.875026 -0.199898)
			(size 0.1778 0.6604)
			(layers "F.Cu" "F.Mask" "F.Paste")
			(net "PVCCIN_CPU1_PWM7")
		)
		(pad "7" smd rect
			(at -2.875026 0.199898)
			(size 0.1778 0.6604)
			(layers "F.Cu" "F.Mask" "F.Paste")
			(net "PVCCIN_CPU1_PWM6")
		)
		(pad "8" smd rect
			(at -2.875026 0.599948)
			(size 0.1778 0.6604)
			(layers "F.Cu" "F.Mask" "F.Paste")
			(net "PVCCIN_CPU1_PWM5")
		)
		(pad "9" smd rect
			(at -2.875026 0.999998)
			(size 0.1778 0.6604)
			(layers "F.Cu" "F.Mask" "F.Paste")
			(net "PVCCIN_CPU1_PWM4")
		)
		(pad "10" smd rect
			(at -2.875026 1.400048)
			(size 0.1778 0.6604)
			(layers "F.Cu" "F.Mask" "F.Paste")
			(net "PVCCIN_CPU1_PWM3")
		)
		(pad "11" smd rect
			(at -2.875026 1.800098)
			(size 0.1778 0.6604)
			(layers "F.Cu" "F.Mask" "F.Paste")
			(net "PVCCIN_CPU1_PWM2")
		)
		(pad "12" smd rect
			(at -2.875026 2.199894)
			(size 0.1778 0.6604)
			(layers "F.Cu" "F.Mask" "F.Paste")
			(net "PVCCIN_CPU1_PWM1")
		)
		(pad "13" smd rect
			(at -2.199894 2.875026 270)
			(size 0.1778 0.6604)
			(layers "F.Cu" "F.Mask" "F.Paste")
			(net "SMB_DIO_PVCCIN_CPU1")
		)
		(pad "14" smd rect
			(at -1.800098 2.875026 270)
			(size 0.1778 0.6604)
			(layers "F.Cu" "F.Mask" "F.Paste")
			(net "SMB_CLK_PVCCIN_CPU1")
		)
		(pad "15" smd rect
			(at -1.400048 2.875026 270)
			(size 0.1778 0.6604)
			(layers "F.Cu" "F.Mask" "F.Paste")
			(net "NC_PVCCIN_CPU1_SMB_ALERT")
		)
		(pad "16" smd rect
			(at -0.999998 2.875026 270)
			(size 0.1778 0.6604)
			(layers "F.Cu" "F.Mask" "F.Paste")
			(net "PWRGD_PVCCIN_CPU1_R")
		)
		(pad "17" smd rect
			(at -0.599948 2.875026 270)
			(size 0.1778 0.6604)
			(layers "F.Cu" "F.Mask" "F.Paste")
			(net "PVCCIN_CPU1_EN_R")
		)
		(pad "18" smd rect
			(at -0.199898 2.875026 270)
			(size 0.1778 0.6604)
			(layers "F.Cu" "F.Mask" "F.Paste")
			(net "IRQ_PVCCIN_CPU1_VRHOT_N")
		)
		(pad "19" smd rect
			(at 0.199898 2.875026 270)
			(size 0.1778 0.6604)
			(layers "F.Cu" "F.Mask" "F.Paste")
			(net "PVCCIN_CPU1_PIN_ALERT")
		)
		(pad "20" smd rect
			(at 0.599948 2.875026 270)
			(size 0.1778 0.6604)
			(layers "F.Cu" "F.Mask" "F.Paste")
			(net "PWRGD_PVCCFA_EHV_FIVRA_CPU1_R")
		)
		(pad "21" smd rect
			(at 0.999998 2.875026 270)
			(size 0.1778 0.6604)
			(layers "F.Cu" "F.Mask" "F.Paste")
			(net "SVID_CLK_PVCCIN_CPU1_R")
		)
		(pad "22" smd rect
			(at 1.400048 2.875026 270)
			(size 0.1778 0.6604)
			(layers "F.Cu" "F.Mask" "F.Paste")
			(net "SVID_DIO_PVCCIN_CPU1_R")
		)
		(pad "23" smd rect
			(at 1.800098 2.875026 270)
			(size 0.1778 0.6604)
			(layers "F.Cu" "F.Mask" "F.Paste")
			(net "SVID_ALERT_PVCCIN_CPU1_R")
		)
		(pad "24" smd rect
			(at 2.199894 2.875026 270)
			(size 0.1778 0.6604)
			(layers "F.Cu" "F.Mask" "F.Paste")
			(net "PVCCFA_EHV_FIVRA_CPU1_EN_R")
		)
		(pad "25" smd rect
			(at 2.875026 2.199894)
			(size 0.1778 0.6604)
			(layers "F.Cu" "F.Mask" "F.Paste")
			(net "SH_PVCCIN_CPU1_R")
		)
		(pad "26" smd rect
			(at 2.875026 1.800098)
			(size 0.1778 0.6604)
			(layers "F.Cu" "F.Mask" "F.Paste")
			(net "VSENSE_PVCCIN_CPU1_DN")
		)
		(pad "27" smd rect
			(at 2.875026 1.400048)
			(size 0.1778 0.6604)
			(layers "F.Cu" "F.Mask" "F.Paste")
			(net "PVCCIN_CPU1_IMON1")
		)
		(pad "28" smd rect
			(at 2.875026 0.999998)
			(size 0.1778 0.6604)
			(layers "F.Cu" "F.Mask" "F.Paste")
			(net "PVCCIN_CPU1_IMON2")
		)
		(pad "29" smd rect
			(at 2.875026 0.599948)
			(size 0.1778 0.6604)
			(layers "F.Cu" "F.Mask" "F.Paste")
			(net "PVCCIN_CPU1_IMON3")
		)
		(pad "30" smd rect
			(at 2.875026 0.199898)
			(size 0.1778 0.6604)
			(layers "F.Cu" "F.Mask" "F.Paste")
			(net "PVCCIN_CPU1_IMON4")
		)
		(pad "31" smd rect
			(at 2.875026 -0.199898)
			(size 0.1778 0.6604)
			(layers "F.Cu" "F.Mask" "F.Paste")
			(net "PVCCIN_CPU1_IMON5")
		)
		(pad "32" smd rect
			(at 2.875026 -0.599948)
			(size 0.1778 0.6604)
			(layers "F.Cu" "F.Mask" "F.Paste")
			(net "PVCCIN_CPU1_IMON6")
		)
		(pad "33" smd rect
			(at 2.875026 -0.999998)
			(size 0.1778 0.6604)
			(layers "F.Cu" "F.Mask" "F.Paste")
			(net "PVCCIN_CPU1_IMON7")
		)
		(pad "34" smd rect
			(at 2.875026 -1.400048)
			(size 0.1778 0.6604)
			(layers "F.Cu" "F.Mask" "F.Paste")
			(net "PVCCIN_CPU1_IMON8")
		)
		(pad "35" smd rect
			(at 2.875026 -1.800098)
			(size 0.1778 0.6604)
			(layers "F.Cu" "F.Mask" "F.Paste")
			(net "PVCCFA_EHV_FIVRA_CPU1_IMON4")
		)
		(pad "36" smd rect
			(at 2.875026 -2.199894)
			(size 0.1778 0.6604)
			(layers "F.Cu" "F.Mask" "F.Paste")
			(net "PVCCFA_EHV_FIVRA_CPU1_IMON3")
		)
		(pad "37" smd rect
			(at 2.199894 -2.875026 270)
			(size 0.1778 0.6604)
			(layers "F.Cu" "F.Mask" "F.Paste")
			(net "PVCCFA_EHV_FIVRA_CPU1_IMON2")
		)
		(pad "38" smd rect
			(at 1.800098 -2.875026 270)
			(size 0.1778 0.6604)
			(layers "F.Cu" "F.Mask" "F.Paste")
			(net "PVCCFA_EHV_FIVRA_CPU1_IMON1")
		)
		(pad "39" smd rect
			(at 1.400048 -2.875026 270)
			(size 0.1778 0.6604)
			(layers "F.Cu" "F.Mask" "F.Paste")
			(net "VSENSE_PVCCFA_EHV_FIVRA_CPU1_DN")
		)
		(pad "40" smd rect
			(at 0.999998 -2.875026 270)
			(size 0.1778 0.6604)
			(layers "F.Cu" "F.Mask" "F.Paste")
			(net "SH_PVCCFA_EHV_FIVRA_CPU1_R")
		)
		(pad "41" smd rect
			(at 0.599948 -2.875026 270)
			(size 0.1778 0.6604)
			(layers "F.Cu" "F.Mask" "F.Paste")
			(net "PVCCIN_CPU1_VR_FAULT")
		)
		(pad "42" smd rect
			(at 0.199898 -2.875026 270)
			(size 0.1778 0.6604)
			(layers "F.Cu" "F.Mask" "F.Paste")
			(net "PVCCIN_CPU1_ADDR")
		)
		(pad "43" smd rect
			(at -0.199898 -2.875026 270)
			(size 0.1778 0.6604)
			(layers "F.Cu" "F.Mask" "F.Paste")
			(net "PVCCIN_CPU1_ATSEN")
		)
		(pad "44" smd rect
			(at -0.599948 -2.875026 270)
			(size 0.1778 0.6604)
			(layers "F.Cu" "F.Mask" "F.Paste")
			(net "PVCCFA_EHV_FIVRA_CPU1_BTSEN")
		)
		(pad "45" smd rect
			(at -0.999998 -2.875026 270)
			(size 0.1778 0.6604)
			(layers "F.Cu" "F.Mask" "F.Paste")
			(net "PVCCIN_CPU1_CSPIN")
		)
		(pad "46" smd rect
			(at -1.400048 -2.875026 270)
			(size 0.1778 0.6604)
			(layers "F.Cu" "F.Mask" "F.Paste")
			(net "PVCCIN_CPU1_VIN_CSNIN")
		)
		(pad "47" smd rect
			(at -1.800098 -2.875026 270)
			(size 0.1778 0.6604)
			(layers "F.Cu" "F.Mask" "F.Paste")
			(net "PVCCIN_CPU1_VCC")
		)
		(pad "48" smd rect
			(at -2.199894 -2.875026 270)
			(size 0.1778 0.6604)
			(layers "F.Cu" "F.Mask" "F.Paste")
			(net "PVCCIN_CPU1_VREF")
		)
		(pad "TH" smd rect
			(at 0 0 270)
			(size 4.4196 4.4196)
			(layers "F.Cu" "F.Mask" "F.Paste")
			(net "GND")
		)
		(zone
			(layer "F.Cu")
			(hatch none 0.5)
			(connect_pads
				(clearance 0)
			)
			(min_thickness 0.25)
			(keepout
				(tracks not_allowed)
				(vias allowed)
				(pads allowed)
				(copperpour not_allowed)
				(footprints allowed)
			)
			(placement
				(enabled no)
				(sheetname "")
			)
			(fill
				(thermal_gap 0.5)
				(thermal_bridge_width 0.5)
				(island_removal_mode 0)
			)
			(polygon
				(pts
					(xy 106.368596 -361.337606) (xy 106.368596 -361.236006) (xy 106.368596 -361.134406) (xy 106.292396 -361.134406)
					(xy 106.292396 -356.562406) (xy 110.864396 -356.562406) (xy 110.864396 -361.134406) (xy 106.393996 -361.134406)
					(xy 106.393996 -361.236006) (xy 106.393996 -361.337606) (xy 111.042196 -361.337606) (xy 111.067596 -361.337606)
					(xy 111.067596 -356.359206) (xy 111.042196 -356.359206) (xy 106.089196 -356.359206) (xy 106.089196 -361.337606)
				)
			)
		)
	)
)
